# S9S_MB_2U (Grand Teton) — schematic netlist excerpt (pin names and nets, part order shuffled) for the footprints in the layout excerpt that follows; sources: Cadence DE-HDL packaged netlist, KiCad conversion of 03242023_DA0F0TMBIJ0_F0T_Motherboard_J_brd_V01_OCP.brd

R977  Q_RES  560 1% CHIP  pkg 0402LF  page 236 : A = P3V3_AUX ; B = SMB_S3M_CPU0_3V3AUX_SCL
PL113  Q_INDUCTOR  130NH/106A IND  pkg SMLF  page 290 : \1\ = SW_PVCCFA_EHV_FIVRA_CPU1_SW4 ; \2\ = PVCCFA_EHV_FIVRA_CPU1

(kicad_pcb
	(version 20260206)
	(generator "pcbnew")
	(generator_version "10.0")
	(general
		(thickness 1.6)
		(legacy_teardrops no)
	)
	(paper "A4")
	(title_block
		(title "03242023_DA0F0TMBIJ0_F0T_Motherboard_J_brd_V01_OCP.brd")
		(comment 1 "Grand Teton / footprints 2224-2225 of 6105")
	)
	(layers
		(0 "F.Cu" signal "TOP")
		(4 "In1.Cu" signal "GND")
		(6 "In2.Cu" signal "IN1")
		(8 "In3.Cu" signal "GND1")
		(10 "In4.Cu" signal "IN2")
		(12 "In5.Cu" signal "GND2")
		(14 "In6.Cu" signal "IN3")
		(16 "In7.Cu" signal "GND3")
		(18 "In8.Cu" signal "VCC")
		(20 "In9.Cu" signal "VCC1")
		(22 "In10.Cu" signal "GND4")
		(24 "In11.Cu" signal "IN4")
		(26 "In12.Cu" signal "GND5")
		(28 "In13.Cu" signal "IN5")
		(30 "In14.Cu" signal "GND6")
		(32 "In15.Cu" signal "IN6")
		(34 "In16.Cu" signal "GND7")
		(2 "B.Cu" signal "BOTTOM")
		(9 "F.Adhes" user "F.Adhesive")
		(11 "B.Adhes" user "B.Adhesive")
		(13 "F.Paste" user "Package Geometry/Pastemask Top")
		(15 "B.Paste" user "Package Geometry/Pastemask Bottom")
		(5 "F.SilkS" user "Ref Des/Silkscreen Top")
		(7 "B.SilkS" user "Ref Des/Silkscreen Bottom")
		(1 "F.Mask" user "Board Geometry/Soldermask Top")
		(3 "B.Mask" user "Board Geometry/Soldermask Bottom")
		(17 "Dwgs.User" user "User.Drawings")
		(19 "Cmts.User" user "User.Comments")
		(21 "Eco1.User" user "User.Eco1")
		(23 "Eco2.User" user "User.Eco2")
		(25 "Edge.Cuts" user "Board Geometry/Outline")
		(27 "Margin" user)
		(31 "F.CrtYd" user "Package Geometry/Place Bound Top")
		(29 "B.CrtYd" user "Package Geometry/Place Bound Bottom")
		(35 "F.Fab" user "Ref Des/Assembly Top")
		(33 "B.Fab" user "Ref Des/Assembly Bottom")
	)
	(footprint ""
		(layer "F.Cu")
		(at 393.37488 -148.808948 90)
		(property "Reference" "R977"
			(at 0 0 90)
			(layer "F.SilkS")
			(hide yes)
			(effects
				(font
					(size 1.27 1.27)
				)
			)
		)
		(property "Value" ""
			(at 0 0 90)
			(layer "F.Fab")
			(effects
				(font
					(size 1.27 1.27)
				)
			)
		)
		(duplicate_pad_numbers_are_jumpers no)
		(fp_line
			(start 0.7874 -0.4064)
			(end 0.7874 0.4064)
			(stroke
				(width 0.1524)
				(type default)
			)
			(layer "F.SilkS")
		)
		(fp_line
			(start -0.7874 -0.4064)
			(end 0.7874 -0.4064)
			(stroke
				(width 0.1524)
				(type default)
			)
			(layer "F.SilkS")
		)
		(fp_line
			(start 0.7874 0.4064)
			(end -0.7874 0.4064)
			(stroke
				(width 0.1524)
				(type default)
			)
			(layer "F.SilkS")
		)
		(fp_line
			(start -0.7874 0.4064)
			(end -0.7874 -0.4064)
			(stroke
				(width 0.1524)
				(type default)
			)
			(layer "F.SilkS")
		)
		(fp_line
			(start -0.12065 -0.305054)
			(end -0.12065 -0.2794)
			(stroke
				(width 0.1)
				(type default)
			)
			(layer "F.Fab")
		)
		(fp_line
			(start -0.67945 -0.305054)
			(end -0.12065 -0.305054)
			(stroke
				(width 0.1)
				(type default)
			)
			(layer "F.Fab")
		)
		(fp_line
			(start 0.67945 -0.3048)
			(end 0.67945 0.3048)
			(stroke
				(width 0.1)
				(type default)
			)
			(layer "F.Fab")
		)
		(fp_line
			(start 0.12065 -0.3048)
			(end 0.67945 -0.3048)
			(stroke
				(width 0.1)
				(type default)
			)
			(layer "F.Fab")
		)
		(fp_line
			(start 0.12065 -0.2794)
			(end 0.12065 -0.3048)
			(stroke
				(width 0.1)
				(type default)
			)
			(layer "F.Fab")
		)
		(fp_line
			(start -0.12065 -0.2794)
			(end 0.12065 -0.2794)
			(stroke
				(width 0.1)
				(type default)
			)
			(layer "F.Fab")
		)
		(fp_line
			(start 0.120396 0.2794)
			(end -0.12065 0.2794)
			(stroke
				(width 0.1)
				(type default)
			)
			(layer "F.Fab")
		)
		(fp_line
			(start -0.12065 0.2794)
			(end -0.12065 0.3048)
			(stroke
				(width 0.1)
				(type default)
			)
			(layer "F.Fab")
		)
		(fp_line
			(start 0.67945 0.3048)
			(end 0.120396 0.3048)
			(stroke
				(width 0.1)
				(type default)
			)
			(layer "F.Fab")
		)
		(fp_line
			(start 0.120396 0.3048)
			(end 0.120396 0.2794)
			(stroke
				(width 0.1)
				(type default)
			)
			(layer "F.Fab")
		)
		(fp_line
			(start -0.12065 0.3048)
			(end -0.67945 0.3048)
			(stroke
				(width 0.1)
				(type default)
			)
			(layer "F.Fab")
		)
		(fp_line
			(start -0.67945 0.3048)
			(end -0.67945 -0.305054)
			(stroke
				(width 0.1)
				(type default)
			)
			(layer "F.Fab")
		)
		(pad "1" smd circle
			(at -0.40005 0 90)
			(size 0 0)
			(layers "F.Cu" "F.Mask" "F.Paste")
			(net "P3V3_AUX")
		)
		(pad "2" smd circle
			(at 0.40005 0 90)
			(size 0 0)
			(layers "F.Cu" "F.Mask" "F.Paste")
			(net "SMB_S3M_CPU0_3V3AUX_SCL")
		)
	)
	(footprint ""
		(layer "F.Cu")
		(at 41.573958 -344.77325 -90)
		(property "Reference" "PL113"
			(at 2.130552 8.226298 0)
			(unlocked yes)
			(layer "F.SilkS")
			(effects
				(font
					(size 0.7874 0.5842)
					(thickness 0.1524)
				)
				(justify left)
			)
		)
		(property "Value" ""
			(at 0 0 270)
			(layer "F.Fab")
			(effects
				(font
					(size 1.27 1.27)
				)
			)
		)
		(duplicate_pad_numbers_are_jumpers no)
		(fp_line
			(start -4.99999 3.750056)
			(end -4.99999 2.2479)
			(stroke
				(width 0.1524)
				(type default)
			)
			(layer "F.SilkS")
		)
		(fp_line
			(start 0 3.750056)
			(end -4.99999 3.750056)
			(stroke
				(width 0.1524)
				(type default)
			)
			(layer "F.SilkS")
		)
		(fp_line
			(start 4.99999 3.750056)
			(end 0 3.750056)
			(stroke
				(width 0.1524)
				(type default)
			)
			(layer "F.SilkS")
		)
		(fp_line
			(start 4.99999 2.2352)
			(end 4.99999 3.750056)
			(stroke
				(width 0.1524)
				(type default)
			)
			(layer "F.SilkS")
		)
		(fp_line
			(start -4.99999 -2.2479)
			(end -4.99999 -3.750056)
			(stroke
				(width 0.1524)
				(type default)
			)
			(layer "F.SilkS")
		)
		(fp_line
			(start -4.99999 -3.750056)
			(end 4.99999 -3.750056)
			(stroke
				(width 0.1524)
				(type default)
			)
			(layer "F.SilkS")
		)
		(fp_line
			(start 4.99999 -3.750056)
			(end 4.99999 -2.2479)
			(stroke
				(width 0.1524)
				(type default)
			)
			(layer "F.SilkS")
		)
		(fp_line
			(start -4.99999 3.750056)
			(end -4.99999 -3.750056)
			(stroke
				(width 0.1)
				(type default)
			)
			(layer "F.Fab")
		)
		(fp_line
			(start 0 3.750056)
			(end -4.99999 3.750056)
			(stroke
				(width 0.1)
				(type default)
			)
			(layer "F.Fab")
		)
		(fp_line
			(start 4.99999 3.750056)
			(end 0 3.750056)
			(stroke
				(width 0.1)
				(type default)
			)
			(layer "F.Fab")
		)
		(fp_line
			(start -4.99999 -3.750056)
			(end 4.99999 -3.750056)
			(stroke
				(width 0.1)
				(type default)
			)
			(layer "F.Fab")
		)
		(fp_line
			(start 4.99999 -3.750056)
			(end 4.99999 3.750056)
			(stroke
				(width 0.1)
				(type default)
			)
			(layer "F.Fab")
		)
		(pad "1" smd rect
			(at -3.299968 0 270)
			(size 3.302 4.2164)
			(layers "F.Cu" "F.Mask" "F.Paste")
			(net "SW_PVCCFA_EHV_FIVRA_CPU1_SW4")
		)
		(pad "2" smd rect
			(at 3.299968 0 270)
			(size 3.302 4.2164)
			(layers "F.Cu" "F.Mask" "F.Paste")
			(net "PVCCFA_EHV_FIVRA_CPU1")
		)
	)
)
